FILE_TYPE = CONNECTIVITY;
{Allegro Design Entry HDL 16.6-p007 (v16-6-112F) 10/10/2012}
"PAGE_NUMBER" = 30;
0"NC";
1"P3E_CPU0_PE1_SS_RXN<7:0>";
2"P3E_CPU0_PE1_SS_RXP<7:0>";
3"P3E_CPU0_PE1_SS_TXN<7:0>";
4"P3E_CPU0_PE1_SS_TXP<7:0>";
5"P3E_CPU0_PE1_PCH_RXN<15:8>";
6"P3E_CPU0_PE1_PCH_RXP<15:8>";
7"P3E_CPU0_PE1_PCH_TXP<15:8>";
8"P3E_CPU0_PE1_PCH_TXN<15:8>";
9"P3E_CPU0_PE1_PCH_TXN<15>";
10"P3E_CPU0_PE1_PCH_RXP<15>";
11"P3E_CPU0_PE1_PCH_TXP<12>";
12"P3E_CPU0_PE1_PCH_RXP<9>";
13"P3E_CPU0_PE1_PCH_RXP<11>";
14"P3E_CPU0_PE1_SS_TXP<1>";
15"P3E_CPU0_PE1_SS_TXP<2>";
16"P3E_CPU0_PE1_SS_TXP<3>";
17"P3E_CPU0_PE1_SS_TXP<4>";
18"P3E_CPU0_PE1_SS_TXP<5>";
19"P3E_CPU0_PE1_SS_TXP<6>";
20"P3E_CPU0_PE1_SS_TXP<7>";
21"P3E_CPU0_PE1_PCH_TXN<9>";
22"P3E_CPU0_PE1_PCH_TXN<10>";
23"P3E_CPU0_PE1_PCH_RXN<8>";
24"P3E_CPU0_PE1_SS_RXN<6>";
25"P3E_CPU0_PE1_SS_RXN<7>";
26"P3E_CPU0_PE1_PCH_TXN<14>";
27"P3E_CPU0_PE1_PCH_TXN<13>";
28"P3E_CPU0_PE1_PCH_TXN<11>";
29"P3E_CPU0_PE1_PCH_TXN<8>";
30"P3E_CPU0_PE1_SS_TXN<7>";
31"P3E_CPU0_PE1_PCH_TXP<15>";
32"P3E_CPU0_PE1_PCH_TXP<14>";
33"P3E_CPU0_PE1_PCH_TXP<13>";
34"P3E_CPU0_PE1_PCH_RXN<11>";
35"P3E_CPU0_PE1_PCH_RXN<10>";
36"P3E_CPU0_PE1_PCH_RXN<9>";
37"P3E_CPU0_PE1_SS_RXN<5>";
38"P3E_CPU0_PE1_SS_RXN<4>";
39"P3E_CPU0_PE1_PCH_RXP<14>";
40"P3E_CPU0_PE1_SS_RXP<7>";
41"P3E_CPU0_PE1_SS_RXP<6>";
42"P3E_CPU0_PE1_SS_RXP<5>";
43"P3E_CPU0_PE1_SS_RXP<4>";
44"P3E_CPU0_PE1_SS_RXN<1>";
45"P3E_CPU0_PE1_SS_RXN<0>";
46"P3E_CPU0_PE1_SS_RXP<3>";
47"P3E_CPU0_PE1_PCH_TXN<12>";
48"P3E_CPU0_PE1_PCH_RXP<10>";
49"P3E_CPU0_PE1_PCH_TXP<9>";
50"P3E_CPU0_PE1_PCH_TXP<11>";
51"P3E_CPU0_PE1_PCH_TXP<10>";
52"P3E_CPU0_PE1_PCH_TXP<8>";
53"P3E_CPU0_PE1_PCH_RXP<12>";
54"P3E_CPU0_PE1_PCH_RXN<12>";
55"P3E_CPU0_PE1_PCH_RXP<13>";
56"P3E_CPU0_PE1_SS_TXN<6>";
57"P3E_CPU0_PE1_PCH_RXP<8>";
58"P3E_CPU0_PE1_PCH_RXN<15>";
59"P3E_CPU0_PE1_PCH_RXN<14>";
60"P3E_CPU0_PE1_PCH_RXN<13>";
61"P3E_CPU0_PE1_SS_TXN<3>";
62"P3E_CPU0_PE1_SS_TXN<2>";
63"P3E_CPU0_PE1_SS_TXN<1>";
64"P3E_CPU0_PE1_SS_TXN<0>";
65"P3E_CPU0_PE1_SS_TXP<0>";
66"P3E_CPU0_PE1_SS_TXN<5>";
67"P3E_CPU0_PE1_SS_TXN<4>";
68"P3E_CPU0_PE1_SS_RXP<2>";
69"P3E_CPU0_PE1_SS_RXP<1>";
70"P3E_CPU0_PE1_SS_RXP<0>";
71"P3E_CPU0_PE1_SS_RXN<3>";
72"P3E_CPU0_PE1_SS_RXN<2>";
%"TAP"
"1","(-5825,1900)","2","mstr_standard","I1";
;
HDL_TAP"TRUE"
BODY_TYPE"PLUMBING"
CDS_LIB"mstr_standard";
"B \NAC \NWC"2;
"S \NAC"
BN"1"69;
%"TAP"
"1","(-5825,2500)","2","mstr_standard","I10";
;
HDL_TAP"TRUE"
BODY_TYPE"PLUMBING"
CDS_LIB"mstr_standard";
"B \NAC \NWC"2;
"S \NAC"
BN"7"40;
%"TAP"
"1","(-5825,2850)","2","mstr_standard","I11";
;
HDL_TAP"TRUE"
BODY_TYPE"PLUMBING"
CDS_LIB"mstr_standard";
"B \NAC \NWC"6;
"S \NAC"
BN"8"57;
%"TAP"
"1","(-5825,2900)","2","mstr_standard","I12";
;
HDL_TAP"TRUE"
BODY_TYPE"PLUMBING"
CDS_LIB"mstr_standard";
"B \NAC \NWC"6;
"S \NAC"
BN"9"12;
%"TAP"
"1","(-5825,2950)","2","mstr_standard","I13";
;
HDL_TAP"TRUE"
BODY_TYPE"PLUMBING"
CDS_LIB"mstr_standard";
"B \NAC \NWC"6;
"S \NAC"
BN"10"48;
%"TAP"
"1","(-5825,3000)","2","mstr_standard","I14";
;
HDL_TAP"TRUE"
BODY_TYPE"PLUMBING"
CDS_LIB"mstr_standard";
"B \NAC \NWC"6;
"S \NAC"
BN"11"13;
%"TAP"
"1","(-5825,3350)","2","mstr_standard","I15";
;
HDL_TAP"TRUE"
BODY_TYPE"PLUMBING"
CDS_LIB"mstr_standard";
"B \NAC \NWC"6;
"S \NAC"
BN"12"53;
%"TAP"
"1","(-5825,3400)","2","mstr_standard","I16";
;
HDL_TAP"TRUE"
BODY_TYPE"PLUMBING"
CDS_LIB"mstr_standard";
"B \NAC \NWC"6;
"S \NAC"
BN"13"55;
%"TAP"
"1","(-5825,3500)","2","mstr_standard","I17";
;
HDL_TAP"TRUE"
BODY_TYPE"PLUMBING"
CDS_LIB"mstr_standard";
"B \NAC \NWC"6;
"S \NAC"
BN"15"10;
%"TAP"
"1","(-5825,3450)","2","mstr_standard","I18";
;
HDL_TAP"TRUE"
BODY_TYPE"PLUMBING"
CDS_LIB"mstr_standard";
"B \NAC \NWC"6;
"S \NAC"
BN"14"39;
%"TAP"
"1","(-5550,1650)","2","mstr_standard","I19";
;
HDL_TAP"TRUE"
BODY_TYPE"PLUMBING"
CDS_LIB"mstr_standard";
"B \NAC \NWC"1;
"S \NAC"
BN"1"44;
%"TAP"
"1","(-5825,1850)","2","mstr_standard","I2";
;
HDL_TAP"TRUE"
BODY_TYPE"PLUMBING"
CDS_LIB"mstr_standard";
"B \NAC \NWC"2;
"S \NAC"
BN"0"70;
%"TAP"
"1","(-5550,1600)","2","mstr_standard","I20";
;
HDL_TAP"TRUE"
BODY_TYPE"PLUMBING"
CDS_LIB"mstr_standard";
"B \NAC \NWC"1;
"S \NAC"
BN"0"45;
%"TAP"
"1","(-5550,1750)","2","mstr_standard","I21";
;
HDL_TAP"TRUE"
BODY_TYPE"PLUMBING"
CDS_LIB"mstr_standard";
"B \NAC \NWC"1;
"S \NAC"
BN"3"71;
%"TAP"
"1","(-5550,1700)","2","mstr_standard","I22";
;
HDL_TAP"TRUE"
BODY_TYPE"PLUMBING"
CDS_LIB"mstr_standard";
"B \NAC \NWC"1;
"S \NAC"
BN"2"72;
%"TAP"
"1","(-5550,2150)","2","mstr_standard","I24";
;
HDL_TAP"TRUE"
BODY_TYPE"PLUMBING"
CDS_LIB"mstr_standard";
"B \NAC \NWC"1;
"S \NAC"
BN"5"37;
%"TAP"
"1","(-5550,2200)","2","mstr_standard","I25";
;
HDL_TAP"TRUE"
BODY_TYPE"PLUMBING"
CDS_LIB"mstr_standard";
"B \NAC \NWC"1;
"S \NAC"
BN"6"24;
%"TAP"
"1","(-5550,2100)","2","mstr_standard","I26";
;
HDL_TAP"TRUE"
BODY_TYPE"PLUMBING"
CDS_LIB"mstr_standard";
"B \NAC \NWC"1;
"S \NAC"
BN"4"38;
%"TAP"
"1","(-5550,2250)","2","mstr_standard","I27";
;
HDL_TAP"TRUE"
BODY_TYPE"PLUMBING"
CDS_LIB"mstr_standard";
"B \NAC \NWC"1;
"S \NAC"
BN"7"25;
%"TAP"
"1","(-5550,2600)","2","mstr_standard","I28";
;
HDL_TAP"TRUE"
BODY_TYPE"PLUMBING"
CDS_LIB"mstr_standard";
"B \NAC \NWC"5;
"S \NAC"
BN"8"23;
%"TAP"
"1","(-5550,2650)","2","mstr_standard","I29";
;
HDL_TAP"TRUE"
BODY_TYPE"PLUMBING"
CDS_LIB"mstr_standard";
"B \NAC \NWC"5;
"S \NAC"
BN"9"36;
%"TAP"
"1","(-5825,1950)","2","mstr_standard","I3";
;
HDL_TAP"TRUE"
BODY_TYPE"PLUMBING"
CDS_LIB"mstr_standard";
"B \NAC \NWC"2;
"S \NAC"
BN"2"68;
%"TAP"
"1","(-5550,2700)","2","mstr_standard","I30";
;
HDL_TAP"TRUE"
BODY_TYPE"PLUMBING"
CDS_LIB"mstr_standard";
"B \NAC \NWC"5;
"S \NAC"
BN"10"35;
%"TAP"
"1","(-5550,2750)","2","mstr_standard","I31";
;
HDL_TAP"TRUE"
BODY_TYPE"PLUMBING"
CDS_LIB"mstr_standard";
"B \NAC \NWC"5;
"S \NAC"
BN"11"34;
%"TAP"
"1","(-5550,3150)","2","mstr_standard","I32";
;
HDL_TAP"TRUE"
BODY_TYPE"PLUMBING"
CDS_LIB"mstr_standard";
"B \NAC \NWC"5;
"S \NAC"
BN"13"60;
%"TAP"
"1","(-5550,3100)","2","mstr_standard","I33";
;
HDL_TAP"TRUE"
BODY_TYPE"PLUMBING"
CDS_LIB"mstr_standard";
"B \NAC \NWC"5;
"S \NAC"
BN"12"54;
%"TAP"
"1","(-5550,3200)","2","mstr_standard","I34";
;
HDL_TAP"TRUE"
BODY_TYPE"PLUMBING"
CDS_LIB"mstr_standard";
"B \NAC \NWC"5;
"S \NAC"
BN"14"59;
%"TAP"
"1","(-5550,3250)","2","mstr_standard","I35";
;
HDL_TAP"TRUE"
BODY_TYPE"PLUMBING"
CDS_LIB"mstr_standard";
"B \NAC \NWC"5;
"S \NAC"
BN"15"58;
%"TAP"
"1","(-2625,1600)","0","mstr_standard","I36";
;
HDL_TAP"TRUE"
BODY_TYPE"PLUMBING"
CDS_LIB"mstr_standard";
"B \NAC \NWC"3;
"S \NAC"
BN"0"64;
%"TAP"
"1","(-2625,1650)","0","mstr_standard","I37";
;
HDL_TAP"TRUE"
BODY_TYPE"PLUMBING"
CDS_LIB"mstr_standard";
"B \NAC \NWC"3;
"S \NAC"
BN"1"63;
%"TAP"
"1","(-2625,1700)","0","mstr_standard","I38";
;
HDL_TAP"TRUE"
BODY_TYPE"PLUMBING"
CDS_LIB"mstr_standard";
"B \NAC \NWC"3;
"S \NAC"
BN"2"62;
%"TAP"
"1","(-2625,1750)","0","mstr_standard","I39";
;
HDL_TAP"TRUE"
BODY_TYPE"PLUMBING"
CDS_LIB"mstr_standard";
"B \NAC \NWC"3;
"S \NAC"
BN"3"61;
%"TAP"
"1","(-2175,1850)","0","mstr_standard","I40";
;
HDL_TAP"TRUE"
BODY_TYPE"PLUMBING"
CDS_LIB"mstr_standard";
"B \NAC \NWC"4;
"S \NAC"
BN"0"65;
%"TAP"
"1","(-2175,1900)","0","mstr_standard","I41";
;
HDL_TAP"TRUE"
BODY_TYPE"PLUMBING"
CDS_LIB"mstr_standard";
"B \NAC \NWC"4;
"S \NAC"
BN"1"14;
%"TAP"
"1","(-2175,1950)","0","mstr_standard","I42";
;
HDL_TAP"TRUE"
BODY_TYPE"PLUMBING"
CDS_LIB"mstr_standard";
"B \NAC \NWC"4;
"S \NAC"
BN"2"15;
%"TAP"
"1","(-2625,2100)","0","mstr_standard","I43";
;
HDL_TAP"TRUE"
BODY_TYPE"PLUMBING"
CDS_LIB"mstr_standard";
"B \NAC \NWC"3;
"S \NAC"
BN"4"67;
%"TAP"
"1","(-2625,2150)","0","mstr_standard","I44";
;
HDL_TAP"TRUE"
BODY_TYPE"PLUMBING"
CDS_LIB"mstr_standard";
"B \NAC \NWC"3;
"S \NAC"
BN"5"66;
%"TAP"
"1","(-2625,2200)","0","mstr_standard","I45";
;
HDL_TAP"TRUE"
BODY_TYPE"PLUMBING"
CDS_LIB"mstr_standard";
"B \NAC \NWC"3;
"S \NAC"
BN"6"56;
%"TAP"
"1","(-2625,2250)","0","mstr_standard","I46";
;
HDL_TAP"TRUE"
BODY_TYPE"PLUMBING"
CDS_LIB"mstr_standard";
"B \NAC \NWC"3;
"S \NAC"
BN"7"30;
%"TAP"
"1","(-2625,2600)","0","mstr_standard","I47";
;
HDL_TAP"TRUE"
BODY_TYPE"PLUMBING"
CDS_LIB"mstr_standard";
"B \NAC \NWC"8;
"S \NAC"
BN"8"29;
%"TAP"
"1","(-2625,2650)","0","mstr_standard","I48";
;
HDL_TAP"TRUE"
BODY_TYPE"PLUMBING"
CDS_LIB"mstr_standard";
"B \NAC \NWC"8;
"S \NAC"
BN"9"21;
%"TAP"
"1","(-2625,2700)","0","mstr_standard","I49";
;
HDL_TAP"TRUE"
BODY_TYPE"PLUMBING"
CDS_LIB"mstr_standard";
"B \NAC \NWC"8;
"S \NAC"
BN"10"22;
%"TAP"
"1","(-2175,2000)","0","mstr_standard","I51";
;
HDL_TAP"TRUE"
BODY_TYPE"PLUMBING"
CDS_LIB"mstr_standard";
"B \NAC \NWC"4;
"S \NAC"
BN"3"16;
%"TAP"
"1","(-2175,2350)","0","mstr_standard","I52";
;
HDL_TAP"TRUE"
BODY_TYPE"PLUMBING"
CDS_LIB"mstr_standard";
"B \NAC \NWC"4;
"S \NAC"
BN"4"17;
%"TAP"
"1","(-2175,2400)","0","mstr_standard","I53";
;
HDL_TAP"TRUE"
BODY_TYPE"PLUMBING"
CDS_LIB"mstr_standard";
"B \NAC \NWC"4;
"S \NAC"
BN"5"18;
%"TAP"
"1","(-2175,2450)","0","mstr_standard","I54";
;
HDL_TAP"TRUE"
BODY_TYPE"PLUMBING"
CDS_LIB"mstr_standard";
"B \NAC \NWC"4;
"S \NAC"
BN"6"19;
%"TAP"
"1","(-2175,2500)","0","mstr_standard","I55";
;
HDL_TAP"TRUE"
BODY_TYPE"PLUMBING"
CDS_LIB"mstr_standard";
"B \NAC \NWC"4;
"S \NAC"
BN"7"20;
%"TAP"
"1","(-2175,2850)","0","mstr_standard","I56";
;
HDL_TAP"TRUE"
BODY_TYPE"PLUMBING"
CDS_LIB"mstr_standard";
"B \NAC \NWC"7;
"S \NAC"
BN"8"52;
%"TAP"
"1","(-2175,2950)","0","mstr_standard","I57";
;
HDL_TAP"TRUE"
BODY_TYPE"PLUMBING"
CDS_LIB"mstr_standard";
"B \NAC \NWC"7;
"S \NAC"
BN"10"51;
%"TAP"
"1","(-2175,2900)","0","mstr_standard","I58";
;
HDL_TAP"TRUE"
BODY_TYPE"PLUMBING"
CDS_LIB"mstr_standard";
"B \NAC \NWC"7;
"S \NAC"
BN"9"49;
%"TAP"
"1","(-2625,3100)","0","mstr_standard","I59";
;
HDL_TAP"TRUE"
BODY_TYPE"PLUMBING"
CDS_LIB"mstr_standard";
"B \NAC \NWC"8;
"S \NAC"
BN"12"47;
%"TAP"
"1","(-5825,2000)","2","mstr_standard","I6";
;
HDL_TAP"TRUE"
BODY_TYPE"PLUMBING"
CDS_LIB"mstr_standard";
"B \NAC \NWC"2;
"S \NAC"
BN"3"46;
%"TAP"
"1","(-2625,3150)","0","mstr_standard","I60";
;
HDL_TAP"TRUE"
BODY_TYPE"PLUMBING"
CDS_LIB"mstr_standard";
"B \NAC \NWC"8;
"S \NAC"
BN"13"27;
%"TAP"
"1","(-2625,3250)","0","mstr_standard","I61";
;
HDL_TAP"TRUE"
BODY_TYPE"PLUMBING"
CDS_LIB"mstr_standard";
"B \NAC \NWC"8;
"S \NAC"
BN"15"9;
%"TAP"
"1","(-2625,3200)","0","mstr_standard","I62";
;
HDL_TAP"TRUE"
BODY_TYPE"PLUMBING"
CDS_LIB"mstr_standard";
"B \NAC \NWC"8;
"S \NAC"
BN"14"26;
%"TAP"
"1","(-2175,3350)","0","mstr_standard","I64";
;
HDL_TAP"TRUE"
BODY_TYPE"PLUMBING"
CDS_LIB"mstr_standard";
"B \NAC \NWC"7;
"S \NAC"
BN"12"11;
%"TAP"
"1","(-2175,3400)","0","mstr_standard","I65";
;
HDL_TAP"TRUE"
BODY_TYPE"PLUMBING"
CDS_LIB"mstr_standard";
"B \NAC \NWC"7;
"S \NAC"
BN"13"33;
%"TAP"
"1","(-2175,3500)","0","mstr_standard","I66";
;
HDL_TAP"TRUE"
BODY_TYPE"PLUMBING"
CDS_LIB"mstr_standard";
"B \NAC \NWC"7;
"S \NAC"
BN"15"31;
%"TAP"
"1","(-2175,3450)","0","mstr_standard","I67";
;
HDL_TAP"TRUE"
BODY_TYPE"PLUMBING"
CDS_LIB"mstr_standard";
"B \NAC \NWC"7;
"S \NAC"
BN"14"32;
%"TAP"
"1","(-5825,2350)","2","mstr_standard","I7";
;
HDL_TAP"TRUE"
BODY_TYPE"PLUMBING"
CDS_LIB"mstr_standard";
"B \NAC \NWC"2;
"S \NAC"
BN"4"43;
%"TAP"
"1","(-2175,3000)","0","mstr_standard","I78";
;
HDL_TAP"TRUE"
BODY_TYPE"PLUMBING"
CDS_LIB"mstr_standard";
"B \NAC \NWC"7;
"S \NAC"
BN"11"50;
%"TAP"
"1","(-2625,2750)","0","mstr_standard","I79";
;
HDL_TAP"TRUE"
BODY_TYPE"PLUMBING"
CDS_LIB"mstr_standard";
"B \NAC \NWC"8;
"S \NAC"
BN"11"28;
%"TAP"
"1","(-5825,2400)","2","mstr_standard","I8";
;
HDL_TAP"TRUE"
BODY_TYPE"PLUMBING"
CDS_LIB"mstr_standard";
"B \NAC \NWC"2;
"S \NAC"
BN"5"42;
%"SKX_EXT_B"
"10","(-4100,2550)","0","chpset_lib","I84";
;
CDS_SEC"10"
MATERIAL"IC"
PART_NUMBER"TBD"
LOCATION"U5D1"
ROOM"CPU0"
CDS_LOCATION"U5D1"
SEC"10"
SEC_TYPE"BGA1"
CDS_LIB"chpset_lib"
PACK_TYPE"BGA1";
"PE1_TX_DP<0>"
$PN"CW2"65;
"PE1_TX_DP<1>"
$PN"DB1"14;
"PE1_TX_DP<2>"
$PN"DD3"15;
"PE1_TX_DP<3>"
$PN"DC4"16;
"PE1_TX_DP<4>"
$PN"DF3"17;
"PE1_TX_DP<5>"
$PN"DH3"18;
"PE1_TX_DP<6>"
$PN"DL2"19;
"PE1_TX_DP<7>"
$PN"DP3"20;
"PE1_TX_DP<8>"
$PN"DR4"52;
"PE1_TX_DP<9>"
$PN"DU2"49;
"PE1_TX_DP<10>"
$PN"DU4"51;
"PE1_TX_DP<11>"
$PN"DV5"50;
"PE1_TX_DP<12>"
$PN"DT7"11;
"PE1_TX_DP<13>"
$PN"DW6"33;
"PE1_TX_DP<14>"
$PN"EB7"32;
"PE1_TX_DP<15>"
$PN"EC8"31;
"PE1_TX_DN<0>"
$PN"DA2"64;
"PE1_TX_DN<1>"
$PN"DC2"63;
"PE1_TX_DN<2>"
$PN"DE2"62;
"PE1_TX_DN<3>"
$PN"DE4"61;
"PE1_TX_DN<4>"
$PN"DG4"67;
"PE1_TX_DN<5>"
$PN"DK3"66;
"PE1_TX_DN<6>"
$PN"DM3"56;
"PE1_TX_DN<7>"
$PN"DN4"30;
"PE1_TX_DN<8>"
$PN"DT5"29;
"PE1_TX_DN<9>"
$PN"DV3"21;
"PE1_TX_DN<10>"
$PN"DW4"22;
"PE1_TX_DN<11>"
$PN"DU6"28;
"PE1_TX_DN<12>"
$PN"DV7"47;
"PE1_TX_DN<13>"
$PN"DY7"27;
"PE1_TX_DN<14>"
$PN"EA8"26;
"PE1_TX_DN<15>"
$PN"ED9"9;
"PE1_RX_DP<0>"
$PN"CU8"70;
"PE1_RX_DP<1>"
$PN"CY7"69;
"PE1_RX_DP<2>"
$PN"DB9"68;
"PE1_RX_DP<3>"
$PN"DA10"46;
"PE1_RX_DP<4>"
$PN"DD9"43;
"PE1_RX_DP<5>"
$PN"DF9"42;
"PE1_RX_DP<6>"
$PN"DJ8"41;
"PE1_RX_DP<7>"
$PN"DL10"40;
"PE1_RX_DP<8>"
$PN"DK11"57;
"PE1_RX_DP<9>"
$PN"DN10"12;
"PE1_RX_DP<10>"
$PN"DR12"48;
"PE1_RX_DP<11>"
$PN"DP13"13;
"PE1_RX_DP<12>"
$PN"DU12"53;
"PE1_RX_DP<13>"
$PN"DY13"55;
"PE1_RX_DP<14>"
$PN"DV15"39;
"PE1_RX_DP<15>"
$PN"DT15"10;
"PE1_RX_DN<0>"
$PN"CW8"45;
"PE1_RX_DN<1>"
$PN"DA8"44;
"PE1_RX_DN<2>"
$PN"DC8"72;
"PE1_RX_DN<3>"
$PN"DC10"71;
"PE1_RX_DN<4>"
$PN"DE10"38;
"PE1_RX_DN<5>"
$PN"DH9"37;
"PE1_RX_DN<6>"
$PN"DK9"24;
"PE1_RX_DN<7>"
$PN"DM9"25;
"PE1_RX_DN<8>"
$PN"DM11"23;
"PE1_RX_DN<9>"
$PN"DP11"36;
"PE1_RX_DN<10>"
$PN"DT11"35;
"PE1_RX_DN<11>"
$PN"DT13"34;
"PE1_RX_DN<12>"
$PN"DV13"54;
"PE1_RX_DN<13>"
$PN"DW14"60;
"PE1_RX_DN<14>"
$PN"DY15"59;
"PE1_RX_DN<15>"
$PN"DU16"58;
%"TAP"
"1","(-5825,2450)","2","mstr_standard","I9";
;
HDL_TAP"TRUE"
BODY_TYPE"PLUMBING"
CDS_LIB"mstr_standard";
"B \NAC \NWC"2;
"S \NAC"
BN"6"41;
END.
